(kicad_pcb
	(version 20260206)
	(generator "pcbnew")
	(generator_version "10.0")
	(general
		(thickness 1.6)
		(legacy_teardrops no)
	)
	(paper "A4")
	(title_block
		(title "01162023_DA0F0TEBIF0_F0T_Expander_BD_F_brd_V02_OCP.brd")
		(comment 1 "Grand Teton / footprint 5329 of 9728 (J27), pads 1-109 of 179")
	)
	(layers
		(0 "F.Cu" signal "TOP")
		(4 "In1.Cu" signal "GND")
		(6 "In2.Cu" signal "VCC")
		(8 "In3.Cu" signal "VCC1")
		(10 "In4.Cu" signal "GND1")
		(12 "In5.Cu" signal "IN1")
		(14 "In6.Cu" signal "GND2")
		(16 "In7.Cu" signal "IN2")
		(18 "In8.Cu" signal "GND3")
		(20 "In9.Cu" signal "IN3")
		(22 "In10.Cu" signal "GND4")
		(24 "In11.Cu" signal "IN4")
		(26 "In12.Cu" signal "GND5")
		(28 "In13.Cu" signal "IN5")
		(30 "In14.Cu" signal "GND6")
		(32 "In15.Cu" signal "IN6")
		(34 "In16.Cu" signal "GND7")
		(2 "B.Cu" signal "BOTTOM")
		(9 "F.Adhes" user "F.Adhesive")
		(11 "B.Adhes" user "B.Adhesive")
		(13 "F.Paste" user "Package Geometry/Pastemask Top")
		(15 "B.Paste" user "Package Geometry/Pastemask Bottom")
		(5 "F.SilkS" user "Ref Des/Silkscreen Top")
		(7 "B.SilkS" user "Ref Des/Silkscreen Bottom")
		(1 "F.Mask" user "Board Geometry/Soldermask Top")
		(3 "B.Mask" user "Board Geometry/Soldermask Bottom")
		(17 "Dwgs.User" user "User.Drawings")
		(19 "Cmts.User" user "User.Comments")
		(21 "Eco1.User" user "User.Eco1")
		(23 "Eco2.User" user "User.Eco2")
		(25 "Edge.Cuts" user "Board Geometry/Outline")
		(27 "Margin" user)
		(31 "F.CrtYd" user "Package Geometry/Place Bound Top")
		(29 "B.CrtYd" user "Package Geometry/Place Bound Bottom")
		(35 "F.Fab" user "Ref Des/Assembly Top")
		(33 "B.Fab" user "Ref Des/Assembly Bottom")
	)
	(footprint ""
		(layer "F.Cu")
		(at 420.280084 -127.700024 180)
		(property "Reference" "J27"
			(at 5.446014 -34.532824 90)
			(unlocked yes)
			(layer "F.SilkS")
			(effects
				(font
					(size 0.7874 0.5842)
					(thickness 0.1524)
				)
				(justify left)
			)
		)
		(property "Value" ""
			(at 0 0 180)
			(layer "F.Fab")
			(effects
				(font
					(size 1.27 1.27)
				)
			)
		)
		(duplicate_pad_numbers_are_jumpers no)
		(pad "" np_thru_hole circle
			(at -0.727456 -32.485076 180)
			(size 1.1176 1.1176)
			(drill 1.1176)
			(layers "*.Cu" "*.Mask")
			(clearance 0.381)
			(thermal_gap 0.381)
		)
		(pad "" np_thru_hole circle
			(at 1.022604 32.485076 180)
			(size 1.1176 1.1176)
			(drill 1.1176)
			(layers "*.Cu" "*.Mask")
			(clearance 0.381)
			(thermal_gap 0.381)
		)
		(pad "A1" smd rect
			(at 3.322574 -18.465038 90)
			(size 0.3556 1.2192)
			(layers "F.Cu" "F.Mask" "F.Paste")
			(net "GND")
		)
		(pad "A2" smd rect
			(at 3.322574 -17.86509 90)
			(size 0.3556 1.2192)
			(layers "F.Cu" "F.Mask" "F.Paste")
			(net "GND")
		)
		(pad "A3" smd rect
			(at 3.322574 -17.264888 90)
			(size 0.3556 1.2192)
			(layers "F.Cu" "F.Mask" "F.Paste")
			(net "GND")
		)
		(pad "A4" smd rect
			(at 3.322574 -16.66494 90)
			(size 0.3556 1.2192)
			(layers "F.Cu" "F.Mask" "F.Paste")
			(net "GND")
		)
		(pad "A5" smd rect
			(at 3.322574 -16.064992 90)
			(size 0.3556 1.2192)
			(layers "F.Cu" "F.Mask" "F.Paste")
			(net "GND")
		)
		(pad "A6" smd rect
			(at 3.322574 -15.465044 90)
			(size 0.3556 1.2192)
			(layers "F.Cu" "F.Mask" "F.Paste")
			(net "GND")
		)
		(pad "A7" smd rect
			(at 3.322574 -14.865096 90)
			(size 0.3556 1.2192)
			(layers "F.Cu" "F.Mask" "F.Paste")
			(net "SMB_NIC7_LS_SCL")
		)
		(pad "A8" smd rect
			(at 3.322574 -14.264894 90)
			(size 0.3556 1.2192)
			(layers "F.Cu" "F.Mask" "F.Paste")
			(net "SMB_NIC7_LS_SDA")
		)
		(pad "A9" smd rect
			(at 3.322574 -13.664946 90)
			(size 0.3556 1.2192)
			(layers "F.Cu" "F.Mask" "F.Paste")
			(net "RST_SMB_NIC7_MUX_ISO_R_N")
		)
		(pad "A10" smd rect
			(at 3.322574 -13.064998 90)
			(size 0.3556 1.2192)
			(layers "F.Cu" "F.Mask" "F.Paste")
			(net "GND")
		)
		(pad "A11" smd rect
			(at 3.322574 -12.46505 90)
			(size 0.3556 1.2192)
			(layers "F.Cu" "F.Mask" "F.Paste")
			(net "RST_NIC7_PERST1_R_N")
		)
		(pad "A12" smd rect
			(at 3.322574 -11.865102 90)
			(size 0.3556 1.2192)
			(layers "F.Cu" "F.Mask" "F.Paste")
			(net "PRSNTB2_NIC7_N")
		)
		(pad "A13" smd rect
			(at 3.322574 -11.2649 90)
			(size 0.3556 1.2192)
			(layers "F.Cu" "F.Mask" "F.Paste")
			(net "GND")
		)
		(pad "A14" smd rect
			(at 3.322574 -10.664952 90)
			(size 0.3556 1.2192)
			(layers "F.Cu" "F.Mask" "F.Paste")
			(net "Net_2666")
		)
		(pad "A15" smd rect
			(at 3.322574 -10.065004 90)
			(size 0.3556 1.2192)
			(layers "F.Cu" "F.Mask" "F.Paste")
			(net "Net_2669")
		)
		(pad "A16" smd rect
			(at 3.322574 -9.465056 90)
			(size 0.3556 1.2192)
			(layers "F.Cu" "F.Mask" "F.Paste")
			(net "GND")
		)
		(pad "A17" smd rect
			(at 3.322574 -8.865108 90)
			(size 0.3556 1.2192)
			(layers "F.Cu" "F.Mask" "F.Paste")
			(net "P5E_PEX3_STN0_RX_DN<0>")
		)
		(pad "A18" smd rect
			(at 3.322574 -8.264906 90)
			(size 0.3556 1.2192)
			(layers "F.Cu" "F.Mask" "F.Paste")
			(net "P5E_PEX3_STN0_RX_DP<0>")
		)
		(pad "A19" smd rect
			(at 3.322574 -7.664958 90)
			(size 0.3556 1.2192)
			(layers "F.Cu" "F.Mask" "F.Paste")
			(net "GND")
		)
		(pad "A20" smd rect
			(at 3.322574 -7.06501 90)
			(size 0.3556 1.2192)
			(layers "F.Cu" "F.Mask" "F.Paste")
			(net "P5E_PEX3_STN0_RX_DN<1>")
		)
		(pad "A21" smd rect
			(at 3.322574 -6.465062 90)
			(size 0.3556 1.2192)
			(layers "F.Cu" "F.Mask" "F.Paste")
			(net "P5E_PEX3_STN0_RX_DP<1>")
		)
		(pad "A22" smd rect
			(at 3.322574 -5.865114 90)
			(size 0.3556 1.2192)
			(layers "F.Cu" "F.Mask" "F.Paste")
			(net "GND")
		)
		(pad "A23" smd rect
			(at 3.322574 -5.264912 90)
			(size 0.3556 1.2192)
			(layers "F.Cu" "F.Mask" "F.Paste")
			(net "P5E_PEX3_STN0_RX_DN<2>")
		)
		(pad "A24" smd rect
			(at 3.322574 -4.664964 90)
			(size 0.3556 1.2192)
			(layers "F.Cu" "F.Mask" "F.Paste")
			(net "P5E_PEX3_STN0_RX_DP<2>")
		)
		(pad "A25" smd rect
			(at 3.322574 -4.065016 90)
			(size 0.3556 1.2192)
			(layers "F.Cu" "F.Mask" "F.Paste")
			(net "GND")
		)
		(pad "A26" smd rect
			(at 3.322574 -3.465068 90)
			(size 0.3556 1.2192)
			(layers "F.Cu" "F.Mask" "F.Paste")
			(net "P5E_PEX3_STN0_RX_DN<3>")
		)
		(pad "A27" smd rect
			(at 3.322574 -2.86512 90)
			(size 0.3556 1.2192)
			(layers "F.Cu" "F.Mask" "F.Paste")
			(net "P5E_PEX3_STN0_RX_DP<3>")
		)
		(pad "A28" smd rect
			(at 3.322574 -2.264918 90)
			(size 0.3556 1.2192)
			(layers "F.Cu" "F.Mask" "F.Paste")
			(net "GND")
		)
		(pad "A29" smd rect
			(at 3.322574 1.74498 90)
			(size 0.3556 1.2192)
			(layers "F.Cu" "F.Mask" "F.Paste")
			(net "GND")
		)
		(pad "A30" smd rect
			(at 3.322574 2.344928 90)
			(size 0.3556 1.2192)
			(layers "F.Cu" "F.Mask" "F.Paste")
			(net "P5E_PEX3_STN0_RX_DN<4>")
		)
		(pad "A31" smd rect
			(at 3.322574 2.944876 90)
			(size 0.3556 1.2192)
			(layers "F.Cu" "F.Mask" "F.Paste")
			(net "P5E_PEX3_STN0_RX_DP<4>")
		)
		(pad "A32" smd rect
			(at 3.322574 3.545078 90)
			(size 0.3556 1.2192)
			(layers "F.Cu" "F.Mask" "F.Paste")
			(net "GND")
		)
		(pad "A33" smd rect
			(at 3.322574 4.145026 90)
			(size 0.3556 1.2192)
			(layers "F.Cu" "F.Mask" "F.Paste")
			(net "P5E_PEX3_STN0_RX_DN<5>")
		)
		(pad "A34" smd rect
			(at 3.322574 4.744974 90)
			(size 0.3556 1.2192)
			(layers "F.Cu" "F.Mask" "F.Paste")
			(net "P5E_PEX3_STN0_RX_DP<5>")
		)
		(pad "A35" smd rect
			(at 3.322574 5.344922 90)
			(size 0.3556 1.2192)
			(layers "F.Cu" "F.Mask" "F.Paste")
			(net "GND")
		)
		(pad "A36" smd rect
			(at 3.322574 5.945124 90)
			(size 0.3556 1.2192)
			(layers "F.Cu" "F.Mask" "F.Paste")
			(net "P5E_PEX3_STN0_RX_DN<6>")
		)
		(pad "A37" smd rect
			(at 3.322574 6.545072 90)
			(size 0.3556 1.2192)
			(layers "F.Cu" "F.Mask" "F.Paste")
			(net "P5E_PEX3_STN0_RX_DP<6>")
		)
		(pad "A38" smd rect
			(at 3.322574 7.14502 90)
			(size 0.3556 1.2192)
			(layers "F.Cu" "F.Mask" "F.Paste")
			(net "GND")
		)
		(pad "A39" smd rect
			(at 3.322574 7.744968 90)
			(size 0.3556 1.2192)
			(layers "F.Cu" "F.Mask" "F.Paste")
			(net "P5E_PEX3_STN0_RX_DN<7>")
		)
		(pad "A40" smd rect
			(at 3.322574 8.344916 90)
			(size 0.3556 1.2192)
			(layers "F.Cu" "F.Mask" "F.Paste")
			(net "P5E_PEX3_STN0_RX_DP<7>")
		)
		(pad "A41" smd rect
			(at 3.322574 8.945118 90)
			(size 0.3556 1.2192)
			(layers "F.Cu" "F.Mask" "F.Paste")
			(net "GND")
		)
		(pad "A42" smd rect
			(at 3.322574 9.545066 90)
			(size 0.3556 1.2192)
			(layers "F.Cu" "F.Mask" "F.Paste")
			(net "PRSNTB1_NIC7_N")
		)
		(pad "A43" smd rect
			(at 3.322574 14.454886 90)
			(size 0.3556 1.2192)
			(layers "F.Cu" "F.Mask" "F.Paste")
			(net "GND")
		)
		(pad "A44" smd rect
			(at 3.322574 15.055088 90)
			(size 0.3556 1.2192)
			(layers "F.Cu" "F.Mask" "F.Paste")
			(net "P5E_PEX3_STN0_RX_DN<8>")
		)
		(pad "A45" smd rect
			(at 3.322574 15.655036 90)
			(size 0.3556 1.2192)
			(layers "F.Cu" "F.Mask" "F.Paste")
			(net "P5E_PEX3_STN0_RX_DP<8>")
		)
		(pad "A46" smd rect
			(at 3.322574 16.254984 90)
			(size 0.3556 1.2192)
			(layers "F.Cu" "F.Mask" "F.Paste")
			(net "GND")
		)
		(pad "A47" smd rect
			(at 3.322574 16.854932 90)
			(size 0.3556 1.2192)
			(layers "F.Cu" "F.Mask" "F.Paste")
			(net "P5E_PEX3_STN0_RX_DN<9>")
		)
		(pad "A48" smd rect
			(at 3.322574 17.45488 90)
			(size 0.3556 1.2192)
			(layers "F.Cu" "F.Mask" "F.Paste")
			(net "P5E_PEX3_STN0_RX_DP<9>")
		)
		(pad "A49" smd rect
			(at 3.322574 18.055082 90)
			(size 0.3556 1.2192)
			(layers "F.Cu" "F.Mask" "F.Paste")
			(net "GND")
		)
		(pad "A50" smd rect
			(at 3.322574 18.65503 90)
			(size 0.3556 1.2192)
			(layers "F.Cu" "F.Mask" "F.Paste")
			(net "P5E_PEX3_STN0_RX_DN<10>")
		)
		(pad "A51" smd rect
			(at 3.322574 19.254978 90)
			(size 0.3556 1.2192)
			(layers "F.Cu" "F.Mask" "F.Paste")
			(net "P5E_PEX3_STN0_RX_DP<10>")
		)
		(pad "A52" smd rect
			(at 3.322574 19.854926 90)
			(size 0.3556 1.2192)
			(layers "F.Cu" "F.Mask" "F.Paste")
			(net "GND")
		)
		(pad "A53" smd rect
			(at 3.322574 20.455128 90)
			(size 0.3556 1.2192)
			(layers "F.Cu" "F.Mask" "F.Paste")
			(net "P5E_PEX3_STN0_RX_DN<11>")
		)
		(pad "A54" smd rect
			(at 3.322574 21.055076 90)
			(size 0.3556 1.2192)
			(layers "F.Cu" "F.Mask" "F.Paste")
			(net "P5E_PEX3_STN0_RX_DP<11>")
		)
		(pad "A55" smd rect
			(at 3.322574 21.655024 90)
			(size 0.3556 1.2192)
			(layers "F.Cu" "F.Mask" "F.Paste")
			(net "GND")
		)
		(pad "A56" smd rect
			(at 3.322574 22.254972 90)
			(size 0.3556 1.2192)
			(layers "F.Cu" "F.Mask" "F.Paste")
			(net "P5E_PEX3_STN0_RX_DN<12>")
		)
		(pad "A57" smd rect
			(at 3.322574 22.85492 90)
			(size 0.3556 1.2192)
			(layers "F.Cu" "F.Mask" "F.Paste")
			(net "P5E_PEX3_STN0_RX_DP<12>")
		)
		(pad "A58" smd rect
			(at 3.322574 23.455122 90)
			(size 0.3556 1.2192)
			(layers "F.Cu" "F.Mask" "F.Paste")
			(net "GND")
		)
		(pad "A59" smd rect
			(at 3.322574 24.05507 90)
			(size 0.3556 1.2192)
			(layers "F.Cu" "F.Mask" "F.Paste")
			(net "P5E_PEX3_STN0_RX_DN<13>")
		)
		(pad "A60" smd rect
			(at 3.322574 24.655018 90)
			(size 0.3556 1.2192)
			(layers "F.Cu" "F.Mask" "F.Paste")
			(net "P5E_PEX3_STN0_RX_DP<13>")
		)
		(pad "A61" smd rect
			(at 3.322574 25.254966 90)
			(size 0.3556 1.2192)
			(layers "F.Cu" "F.Mask" "F.Paste")
			(net "GND")
		)
		(pad "A62" smd rect
			(at 3.322574 25.854914 90)
			(size 0.3556 1.2192)
			(layers "F.Cu" "F.Mask" "F.Paste")
			(net "P5E_PEX3_STN0_RX_DN<14>")
		)
		(pad "A63" smd rect
			(at 3.322574 26.455116 90)
			(size 0.3556 1.2192)
			(layers "F.Cu" "F.Mask" "F.Paste")
			(net "P5E_PEX3_STN0_RX_DP<14>")
		)
		(pad "A64" smd rect
			(at 3.322574 27.055064 90)
			(size 0.3556 1.2192)
			(layers "F.Cu" "F.Mask" "F.Paste")
			(net "GND")
		)
		(pad "A65" smd rect
			(at 3.322574 27.655012 90)
			(size 0.3556 1.2192)
			(layers "F.Cu" "F.Mask" "F.Paste")
			(net "P5E_PEX3_STN0_RX_DN<15>")
		)
		(pad "A66" smd rect
			(at 3.322574 28.25496 90)
			(size 0.3556 1.2192)
			(layers "F.Cu" "F.Mask" "F.Paste")
			(net "P5E_PEX3_STN0_RX_DP<15>")
		)
		(pad "A67" smd rect
			(at 3.322574 28.854908 90)
			(size 0.3556 1.2192)
			(layers "F.Cu" "F.Mask" "F.Paste")
			(net "GND")
		)
		(pad "A68" smd rect
			(at 3.322574 29.45511 90)
			(size 0.3556 1.2192)
			(layers "F.Cu" "F.Mask" "F.Paste")
			(net "Net_2674")
		)
		(pad "A69" smd rect
			(at 3.322574 30.055058 90)
			(size 0.3556 1.2192)
			(layers "F.Cu" "F.Mask" "F.Paste")
			(net "Net_2675")
		)
		(pad "A70" smd rect
			(at 3.322574 30.655006 90)
			(size 0.3556 1.2192)
			(layers "F.Cu" "F.Mask" "F.Paste")
			(net "NIC7_PWRBRK_R_N")
		)
		(pad "B1" smd rect
			(at -1.27762 -18.465038 90)
			(size 0.3556 1.2192)
			(layers "F.Cu" "F.Mask" "F.Paste")
			(net "P12V_NIC7")
		)
		(pad "B2" smd rect
			(at -1.27762 -17.86509 90)
			(size 0.3556 1.2192)
			(layers "F.Cu" "F.Mask" "F.Paste")
			(net "P12V_NIC7")
		)
		(pad "B3" smd rect
			(at -1.27762 -17.264888 90)
			(size 0.3556 1.2192)
			(layers "F.Cu" "F.Mask" "F.Paste")
			(net "P12V_NIC7")
		)
		(pad "B4" smd rect
			(at -1.27762 -16.66494 90)
			(size 0.3556 1.2192)
			(layers "F.Cu" "F.Mask" "F.Paste")
			(net "P12V_NIC7")
		)
		(pad "B5" smd rect
			(at -1.27762 -16.064992 90)
			(size 0.3556 1.2192)
			(layers "F.Cu" "F.Mask" "F.Paste")
			(net "P12V_NIC7")
		)
		(pad "B6" smd rect
			(at -1.27762 -15.465044 90)
			(size 0.3556 1.2192)
			(layers "F.Cu" "F.Mask" "F.Paste")
			(net "P12V_NIC7")
		)
		(pad "B7" smd rect
			(at -1.27762 -14.865096 90)
			(size 0.3556 1.2192)
			(layers "F.Cu" "F.Mask" "F.Paste")
			(net "NIC7_BIF0_N")
		)
		(pad "B8" smd rect
			(at -1.27762 -14.264894 90)
			(size 0.3556 1.2192)
			(layers "F.Cu" "F.Mask" "F.Paste")
			(net "NIC7_BIF1_N")
		)
		(pad "B9" smd rect
			(at -1.27762 -13.664946 90)
			(size 0.3556 1.2192)
			(layers "F.Cu" "F.Mask" "F.Paste")
			(net "NIC7_BIF2_N")
		)
		(pad "B10" smd rect
			(at -1.27762 -13.064998 90)
			(size 0.3556 1.2192)
			(layers "F.Cu" "F.Mask" "F.Paste")
			(net "RST_NIC7_PERST0_R_N")
		)
		(pad "B11" smd rect
			(at -1.27762 -12.46505 90)
			(size 0.3556 1.2192)
			(layers "F.Cu" "F.Mask" "F.Paste")
			(net "P3V3_NIC7")
		)
		(pad "B12" smd rect
			(at -1.27762 -11.865102 90)
			(size 0.3556 1.2192)
			(layers "F.Cu" "F.Mask" "F.Paste")
			(net "NIC7_AUX_PWR_EN_R")
		)
		(pad "B13" smd rect
			(at -1.27762 -11.2649 90)
			(size 0.3556 1.2192)
			(layers "F.Cu" "F.Mask" "F.Paste")
			(net "GND")
		)
		(pad "B14" smd rect
			(at -1.27762 -10.664952 90)
			(size 0.3556 1.2192)
			(layers "F.Cu" "F.Mask" "F.Paste")
			(net "CLK_100M_DB2000QL_NIC7_R_DN")
		)
		(pad "B15" smd rect
			(at -1.27762 -10.065004 90)
			(size 0.3556 1.2192)
			(layers "F.Cu" "F.Mask" "F.Paste")
			(net "CLK_100M_DB2000QL_NIC7_R_DP")
		)
		(pad "B16" smd rect
			(at -1.27762 -9.465056 90)
			(size 0.3556 1.2192)
			(layers "F.Cu" "F.Mask" "F.Paste")
			(net "GND")
		)
		(pad "B17" smd rect
			(at -1.27762 -8.865108 90)
			(size 0.3556 1.2192)
			(layers "F.Cu" "F.Mask" "F.Paste")
			(net "P5E_PEX3_STN0_TX_C_DN<0>")
		)
		(pad "B18" smd rect
			(at -1.27762 -8.264906 90)
			(size 0.3556 1.2192)
			(layers "F.Cu" "F.Mask" "F.Paste")
			(net "P5E_PEX3_STN0_TX_C_DP<0>")
		)
		(pad "B19" smd rect
			(at -1.27762 -7.664958 90)
			(size 0.3556 1.2192)
			(layers "F.Cu" "F.Mask" "F.Paste")
			(net "GND")
		)
		(pad "B20" smd rect
			(at -1.27762 -7.06501 90)
			(size 0.3556 1.2192)
			(layers "F.Cu" "F.Mask" "F.Paste")
			(net "P5E_PEX3_STN0_TX_C_DN<1>")
		)
		(pad "B21" smd rect
			(at -1.27762 -6.465062 90)
			(size 0.3556 1.2192)
			(layers "F.Cu" "F.Mask" "F.Paste")
			(net "P5E_PEX3_STN0_TX_C_DP<1>")
		)
		(pad "B22" smd rect
			(at -1.27762 -5.865114 90)
			(size 0.3556 1.2192)
			(layers "F.Cu" "F.Mask" "F.Paste")
			(net "GND")
		)
		(pad "B23" smd rect
			(at -1.27762 -5.264912 90)
			(size 0.3556 1.2192)
			(layers "F.Cu" "F.Mask" "F.Paste")
			(net "P5E_PEX3_STN0_TX_C_DN<2>")
		)
		(pad "B24" smd rect
			(at -1.27762 -4.664964 90)
			(size 0.3556 1.2192)
			(layers "F.Cu" "F.Mask" "F.Paste")
			(net "P5E_PEX3_STN0_TX_C_DP<2>")
		)
		(pad "B25" smd rect
			(at -1.27762 -4.065016 90)
			(size 0.3556 1.2192)
			(layers "F.Cu" "F.Mask" "F.Paste")
			(net "GND")
		)
		(pad "B26" smd rect
			(at -1.27762 -3.465068 90)
			(size 0.3556 1.2192)
			(layers "F.Cu" "F.Mask" "F.Paste")
			(net "P5E_PEX3_STN0_TX_C_DN<3>")
		)
		(pad "B27" smd rect
			(at -1.27762 -2.86512 90)
			(size 0.3556 1.2192)
			(layers "F.Cu" "F.Mask" "F.Paste")
			(net "P5E_PEX3_STN0_TX_C_DP<3>")
		)
		(pad "B28" smd rect
			(at -1.27762 -2.264918 90)
			(size 0.3556 1.2192)
			(layers "F.Cu" "F.Mask" "F.Paste")
			(net "GND")
		)
		(pad "B29" smd rect
			(at -1.27762 1.74498 90)
			(size 0.3556 1.2192)
			(layers "F.Cu" "F.Mask" "F.Paste")
			(net "GND")
		)
		(pad "B30" smd rect
			(at -1.27762 2.344928 90)
			(size 0.3556 1.2192)
			(layers "F.Cu" "F.Mask" "F.Paste")
			(net "P5E_PEX3_STN0_TX_C_DN<4>")
		)
		(pad "B31" smd rect
			(at -1.27762 2.944876 90)
			(size 0.3556 1.2192)
			(layers "F.Cu" "F.Mask" "F.Paste")
			(net "P5E_PEX3_STN0_TX_C_DP<4>")
		)
		(pad "B32" smd rect
			(at -1.27762 3.545078 90)
			(size 0.3556 1.2192)
			(layers "F.Cu" "F.Mask" "F.Paste")
			(net "GND")
		)
		(pad "B33" smd rect
			(at -1.27762 4.145026 90)
			(size 0.3556 1.2192)
			(layers "F.Cu" "F.Mask" "F.Paste")
			(net "P5E_PEX3_STN0_TX_C_DN<5>")
		)
		(pad "B34" smd rect
			(at -1.27762 4.744974 90)
			(size 0.3556 1.2192)
			(layers "F.Cu" "F.Mask" "F.Paste")
			(net "P5E_PEX3_STN0_TX_C_DP<5>")
		)
		(pad "B35" smd rect
			(at -1.27762 5.344922 90)
			(size 0.3556 1.2192)
			(layers "F.Cu" "F.Mask" "F.Paste")
			(net "GND")
		)
		(pad "B36" smd rect
			(at -1.27762 5.945124 90)
			(size 0.3556 1.2192)
			(layers "F.Cu" "F.Mask" "F.Paste")
			(net "P5E_PEX3_STN0_TX_C_DN<6>")
		)
		(pad "B37" smd rect
			(at -1.27762 6.545072 90)
			(size 0.3556 1.2192)
			(layers "F.Cu" "F.Mask" "F.Paste")
			(net "P5E_PEX3_STN0_TX_C_DP<6>")
		)
	)
)
